(kicad_pcb
	(version 20221018)
	(generator pcbnew)
	(general
    (thickness 1.518)
  )
	(paper "A4")
	(title_block
    (title "Kria K26 Devboard")
    (date "2024-03-26")
    (rev "1.2.5")
    (comment 1 "www.antmicro.com")
    (comment 2 "Antmicro Ltd.")
		(comment 9 "footprints 449-458 of 660")
	)
	(layers
    (0 "F.Cu" mixed)
    (1 "In1.Cu" power)
    (2 "In2.Cu" mixed)
    (3 "In3.Cu" power)
    (4 "In4.Cu" mixed)
    (5 "In5.Cu" power)
    (6 "In6.Cu" mixed)
    (31 "B.Cu" power)
    (32 "B.Adhes" user "B.Adhesive")
    (33 "F.Adhes" user "F.Adhesive")
    (34 "B.Paste" user)
    (35 "F.Paste" user)
    (36 "B.SilkS" user "B.Silkscreen")
    (37 "F.SilkS" user "F.Silkscreen")
    (38 "B.Mask" user)
    (39 "F.Mask" user)
    (40 "Dwgs.User" user "User.Drawings")
    (41 "Cmts.User" user "User.Comments")
    (42 "Eco1.User" user "User.Eco1")
    (43 "Eco2.User" user "User.Eco2")
    (44 "Edge.Cuts" user)
    (45 "Margin" user)
    (46 "B.CrtYd" user "B.Courtyard")
    (47 "F.CrtYd" user "F.Courtyard")
    (48 "B.Fab" user)
    (49 "F.Fab" user)
  )
	(footprint "kria-k26-devboard-footprints:C_0402_1005Metric" (layer "B.Cu")
    (at 104.35 140.425 90)
    (descr "Capacitor SMD 0402")
    (tags "capacitor SMD 0402")
    (property "Author" "Antmicro")
    (property "Dielectric" "X5R")
    (property "License" "Apache-2.0")
    (property "MPN" "GRM155R61H104KE14D")
    (property "Manufacturer" "Murata")
    (property "Sheetfile" "reset.kicad_sch")
    (property "Sheetname" "Reset logic")
    (property "Val" "100n")
    (property "Voltage" "50V")
    (property "ki_description" " ")
    (attr smd)
    (fp_text reference "C132" (at 1.415 -0.59 270) (layer "B.SilkS")
        (effects (font (size 0.7 0.7) (thickness 0.15)) (justify left bottom mirror))
    )
    (fp_text value "C_100n_0402" (at 0 -1.4 270) (layer "B.Fab") hide
        (effects (font (size 0.7 0.7) (thickness 0.15)) (justify left bottom mirror))
    )
    (fp_text user "License: Apache-2.0" (at -0.932 -5.17 270) (layer "B.Fab") hide
        (effects (font (size 0.7 0.7) (thickness 0.15)) (justify left bottom mirror))
    )
    (fp_text user "Author: Antmicro" (at -0.932 -4.17 270) (layer "B.Fab") hide
        (effects (font (size 0.7 0.7) (thickness 0.15)) (justify left bottom mirror))
    )
    (fp_text user "${REFERENCE}" (at -0.932 -3.168 270) (layer "B.Fab") hide
        (effects (font (size 0.7 0.7) (thickness 0.15)) (justify left bottom mirror))
    )
    (fp_rect (start -0.94 0.47) (end 0.94 -0.47)
      (stroke (width 0.05) (type solid)) (fill none) (layer "B.CrtYd"))
    (fp_rect (start -0.499 0.249) (end 0.499 -0.249)
      (stroke (width 0.15) (type solid)) (fill none) (layer "B.Fab"))
    (pad "1" smd roundrect (at -0.484 0 90) (size 0.59 0.64) (layers "B.Cu" "B.Paste" "B.Mask") (roundrect_rratio 0.25)
      (net 15 "PS_3V3") (pintype "passive"))
    (pad "2" smd roundrect (at 0.484 0 90) (size 0.59 0.64) (layers "B.Cu" "B.Paste" "B.Mask") (roundrect_rratio 0.25)
      (net 1 "GND") (pintype "passive"))
  )
	(footprint "kria-k26-devboard-footprints:C_0402_1005Metric" (layer "B.Cu")
    (at 108.48 141.6)
    (descr "Capacitor SMD 0402")
    (tags "capacitor SMD 0402")
    (property "Author" "Antmicro")
    (property "Dielectric" "X5R")
    (property "License" "Apache-2.0")
    (property "MPN" "GRM155R61H104KE14D")
    (property "Manufacturer" "Murata")
    (property "Sheetfile" "reset.kicad_sch")
    (property "Sheetname" "Reset logic")
    (property "Val" "100n")
    (property "Voltage" "50V")
    (property "ki_description" " ")
    (attr smd)
    (fp_text reference "C136" (at 1.52 1.31 180) (layer "B.SilkS")
        (effects (font (size 0.7 0.7) (thickness 0.15)) (justify left bottom mirror))
    )
    (fp_text value "C_100n_0402" (at 0 -1.4 180) (layer "B.Fab") hide
        (effects (font (size 0.7 0.7) (thickness 0.15)) (justify left bottom mirror))
    )
    (fp_text user "${REFERENCE}" (at -0.932 -3.168 180) (layer "B.Fab") hide
        (effects (font (size 0.7 0.7) (thickness 0.15)) (justify left bottom mirror))
    )
    (fp_text user "Author: Antmicro" (at -0.932 -4.17 180) (layer "B.Fab") hide
        (effects (font (size 0.7 0.7) (thickness 0.15)) (justify left bottom mirror))
    )
    (fp_text user "License: Apache-2.0" (at -0.932 -5.17 180) (layer "B.Fab") hide
        (effects (font (size 0.7 0.7) (thickness 0.15)) (justify left bottom mirror))
    )
    (fp_rect (start -0.94 0.47) (end 0.94 -0.47)
      (stroke (width 0.05) (type solid)) (fill none) (layer "B.CrtYd"))
    (fp_rect (start -0.499 0.249) (end 0.499 -0.249)
      (stroke (width 0.15) (type solid)) (fill none) (layer "B.Fab"))
    (pad "1" smd roundrect (at -0.484 0) (size 0.59 0.64) (layers "B.Cu" "B.Paste" "B.Mask") (roundrect_rratio 0.25)
      (net 15 "PS_3V3") (pintype "passive"))
    (pad "2" smd roundrect (at 0.484 0) (size 0.59 0.64) (layers "B.Cu" "B.Paste" "B.Mask") (roundrect_rratio 0.25)
      (net 1 "GND") (pintype "passive"))
  )
	(footprint "kria-k26-devboard-footprints:R_0402_1005Metric" (layer "B.Cu")
    (at 115.685 140.1 180)
    (descr "Resistor SMD 0402")
    (tags "resistor SMD 0402")
    (property "Author" "Antmicro")
    (property "License" "Apache-2.0")
    (property "MPN" "CR0402-FX-1003GLF")
    (property "Manufacturer" "Bourns")
    (property "Sheetfile" "reset.kicad_sch")
    (property "Sheetname" "Reset logic")
    (property "Tolerance" "1%")
    (property "Val" "100k")
    (property "ki_description" "100k resistor in 0402 package with 1% tolerance")
    (attr smd)
    (fp_text reference "R90" (at -3.07 -0.34) (layer "B.SilkS")
        (effects (font (size 0.7 0.7) (thickness 0.15)) (justify left bottom mirror))
    )
    (fp_text value "R_100k_0402" (at 0 -1.4) (layer "B.Fab") hide
        (effects (font (size 0.7 0.7) (thickness 0.15)) (justify left bottom mirror))
    )
    (fp_text user "${REFERENCE}" (at -0.95 -3.168) (layer "B.Fab") hide
        (effects (font (size 0.7 0.7) (thickness 0.15)) (justify left bottom mirror))
    )
    (fp_text user "Author: Antmicro" (at -0.95 -4.169) (layer "B.Fab") hide
        (effects (font (size 0.7 0.7) (thickness 0.15)) (justify left bottom mirror))
    )
    (fp_text user "License: Apache-2.0" (at -0.95 -5.169) (layer "B.Fab") hide
        (effects (font (size 0.7 0.7) (thickness 0.15)) (justify left bottom mirror))
    )
    (fp_rect (start -0.93 0.47) (end 0.93 -0.47)
      (stroke (width 0.05) (type solid)) (fill none) (layer "B.CrtYd"))
    (fp_rect (start -0.5 0.25) (end 0.5 -0.25)
      (stroke (width 0.15) (type solid)) (fill none) (layer "B.Fab"))
    (pad "1" smd roundrect (at -0.485 0 180) (size 0.59 0.64) (layers "B.Cu" "B.Paste" "B.Mask") (roundrect_rratio 0.25)
      (net 1 "GND") (pintype "passive"))
    (pad "2" smd roundrect (at 0.485 0 180) (size 0.59 0.64) (layers "B.Cu" "B.Paste" "B.Mask") (roundrect_rratio 0.25)
      (net 678 "Net-(U33-2A1)") (pintype "passive"))
  )
	(footprint "kria-k26-devboard-footprints:C_0402_1005Metric" (layer "B.Cu")
    (at 107.05 144.9 180)
    (descr "Capacitor SMD 0402")
    (tags "capacitor SMD 0402")
    (property "Author" "Antmicro")
    (property "Dielectric" "X5R")
    (property "License" "Apache-2.0")
    (property "MPN" "GRM155R61H104KE14D")
    (property "Manufacturer" "Murata")
    (property "Sheetfile" "reset.kicad_sch")
    (property "Sheetname" "Reset logic")
    (property "Val" "100n")
    (property "Voltage" "50V")
    (property "ki_description" " ")
    (attr smd)
    (fp_text reference "C137" (at -0.395 -1.31) (layer "B.SilkS")
        (effects (font (size 0.7 0.7) (thickness 0.15)) (justify left bottom mirror))
    )
    (fp_text value "C_100n_0402" (at 0 -1.4) (layer "B.Fab") hide
        (effects (font (size 0.7 0.7) (thickness 0.15)) (justify left bottom mirror))
    )
    (fp_text user "License: Apache-2.0" (at -0.932 -5.17) (layer "B.Fab") hide
        (effects (font (size 0.7 0.7) (thickness 0.15)) (justify left bottom mirror))
    )
    (fp_text user "${REFERENCE}" (at -0.932 -3.168) (layer "B.Fab") hide
        (effects (font (size 0.7 0.7) (thickness 0.15)) (justify left bottom mirror))
    )
    (fp_text user "Author: Antmicro" (at -0.932 -4.17) (layer "B.Fab") hide
        (effects (font (size 0.7 0.7) (thickness 0.15)) (justify left bottom mirror))
    )
    (fp_rect (start -0.94 0.47) (end 0.94 -0.47)
      (stroke (width 0.05) (type solid)) (fill none) (layer "B.CrtYd"))
    (fp_rect (start -0.499 0.249) (end 0.499 -0.249)
      (stroke (width 0.15) (type solid)) (fill none) (layer "B.Fab"))
    (pad "1" smd roundrect (at -0.484 0 180) (size 0.59 0.64) (layers "B.Cu" "B.Paste" "B.Mask") (roundrect_rratio 0.25)
      (net 17 "PS_1V8") (pintype "passive"))
    (pad "2" smd roundrect (at 0.484 0 180) (size 0.59 0.64) (layers "B.Cu" "B.Paste" "B.Mask") (roundrect_rratio 0.25)
      (net 1 "GND") (pintype "passive"))
  )
	(footprint "kria-k26-devboard-footprints:C_0402_1005Metric" (layer "B.Cu")
    (at 101.75 141.9)
    (descr "Capacitor SMD 0402")
    (tags "capacitor SMD 0402")
    (property "Author" "Antmicro")
    (property "Dielectric" "")
    (property "License" "Apache-2.0")
    (property "MPN" "MC0402X473K160CT")
    (property "Manufacturer" "Multicomp")
    (property "Sheetfile" "reset.kicad_sch")
    (property "Sheetname" "Reset logic")
    (property "Val" "47n")
    (property "Voltage" "")
    (property "ki_description" " ")
    (attr smd)
    (fp_text reference "C131" (at 1.35 1.33 180) (layer "B.SilkS")
        (effects (font (size 0.7 0.7) (thickness 0.15)) (justify left bottom mirror))
    )
    (fp_text value "C_47n_0402" (at 0 -1.4 180) (layer "B.Fab") hide
        (effects (font (size 0.7 0.7) (thickness 0.15)) (justify left bottom mirror))
    )
    (fp_text user "Author: Antmicro" (at -0.932 -4.17 180) (layer "B.Fab") hide
        (effects (font (size 0.7 0.7) (thickness 0.15)) (justify left bottom mirror))
    )
    (fp_text user "${REFERENCE}" (at -0.932 -3.168 180) (layer "B.Fab") hide
        (effects (font (size 0.7 0.7) (thickness 0.15)) (justify left bottom mirror))
    )
    (fp_text user "License: Apache-2.0" (at -0.932 -5.17 180) (layer "B.Fab") hide
        (effects (font (size 0.7 0.7) (thickness 0.15)) (justify left bottom mirror))
    )
    (fp_rect (start -0.94 0.47) (end 0.94 -0.47)
      (stroke (width 0.05) (type solid)) (fill none) (layer "B.CrtYd"))
    (fp_rect (start -0.499 0.249) (end 0.499 -0.249)
      (stroke (width 0.15) (type solid)) (fill none) (layer "B.Fab"))
    (pad "1" smd roundrect (at -0.484 0) (size 0.59 0.64) (layers "B.Cu" "B.Paste" "B.Mask") (roundrect_rratio 0.25)
      (net 247 "Net-(U31-CT)") (pintype "passive"))
    (pad "2" smd roundrect (at 0.484 0) (size 0.59 0.64) (layers "B.Cu" "B.Paste" "B.Mask") (roundrect_rratio 0.25)
      (net 1 "GND") (pintype "passive"))
  )
	(footprint "kria-k26-devboard-footprints:R_0402_1005Metric" (layer "B.Cu")
    (at 109.65 139.665 -90)
    (descr "Resistor SMD 0402")
    (tags "resistor SMD 0402")
    (property "Author" "Antmicro")
    (property "License" "Apache-2.0")
    (property "MPN" "CR0402-FX-1003GLF")
    (property "Manufacturer" "Bourns")
    (property "Sheetfile" "reset.kicad_sch")
    (property "Sheetname" "Reset logic")
    (property "Tolerance" "1%")
    (property "Val" "100k")
    (property "ki_description" "100k resistor in 0402 package with 1% tolerance")
    (attr smd)
    (fp_text reference "R89" (at -0.995 0.59 90) (layer "B.SilkS")
        (effects (font (size 0.7 0.7) (thickness 0.15)) (justify left bottom mirror))
    )
    (fp_text value "R_100k_0402" (at 0 -1.4 90) (layer "B.Fab") hide
        (effects (font (size 0.7 0.7) (thickness 0.15)) (justify left bottom mirror))
    )
    (fp_text user "License: Apache-2.0" (at -0.95 -5.169 90) (layer "B.Fab") hide
        (effects (font (size 0.7 0.7) (thickness 0.15)) (justify left bottom mirror))
    )
    (fp_text user "Author: Antmicro" (at -0.95 -4.169 90) (layer "B.Fab") hide
        (effects (font (size 0.7 0.7) (thickness 0.15)) (justify left bottom mirror))
    )
    (fp_text user "${REFERENCE}" (at -0.95 -3.168 90) (layer "B.Fab") hide
        (effects (font (size 0.7 0.7) (thickness 0.15)) (justify left bottom mirror))
    )
    (fp_rect (start -0.93 0.47) (end 0.93 -0.47)
      (stroke (width 0.05) (type solid)) (fill none) (layer "B.CrtYd"))
    (fp_rect (start -0.5 0.25) (end 0.5 -0.25)
      (stroke (width 0.15) (type solid)) (fill none) (layer "B.Fab"))
    (pad "1" smd roundrect (at -0.485 0 270) (size 0.59 0.64) (layers "B.Cu" "B.Paste" "B.Mask") (roundrect_rratio 0.25)
      (net 1 "GND") (pintype "passive"))
    (pad "2" smd roundrect (at 0.485 0 270) (size 0.59 0.64) (layers "B.Cu" "B.Paste" "B.Mask") (roundrect_rratio 0.25)
      (net 677 "Net-(U33-1A2)") (pintype "passive"))
  )
	(footprint "kria-k26-devboard-footprints:R_0402_1005Metric" (layer "B.Cu")
    (at 115.7 143.1 180)
    (descr "Resistor SMD 0402")
    (tags "resistor SMD 0402")
    (property "Author" "Antmicro")
    (property "License" "Apache-2.0")
    (property "MPN" "CR0402-FX-1002GLF")
    (property "Manufacturer" "Bourns")
    (property "Sheetfile" "reset.kicad_sch")
    (property "Sheetname" "Reset logic")
    (property "Tolerance" "1%")
    (property "Val" "10k")
    (property "ki_description" "10k resistor in 0402 package with 1% tolerance")
    (attr smd)
    (fp_text reference "R93" (at -3.07 -0.34) (layer "B.SilkS")
        (effects (font (size 0.7 0.7) (thickness 0.15)) (justify left bottom mirror))
    )
    (fp_text value "R_10k_0402" (at 0 -1.4) (layer "B.Fab") hide
        (effects (font (size 0.7 0.7) (thickness 0.15)) (justify left bottom mirror))
    )
    (fp_text user "Author: Antmicro" (at -0.95 -4.169) (layer "B.Fab") hide
        (effects (font (size 0.7 0.7) (thickness 0.15)) (justify left bottom mirror))
    )
    (fp_text user "License: Apache-2.0" (at -0.95 -5.169) (layer "B.Fab") hide
        (effects (font (size 0.7 0.7) (thickness 0.15)) (justify left bottom mirror))
    )
    (fp_text user "${REFERENCE}" (at -0.95 -3.168) (layer "B.Fab") hide
        (effects (font (size 0.7 0.7) (thickness 0.15)) (justify left bottom mirror))
    )
    (fp_rect (start -0.93 0.47) (end 0.93 -0.47)
      (stroke (width 0.05) (type solid)) (fill none) (layer "B.CrtYd"))
    (fp_rect (start -0.5 0.25) (end 0.5 -0.25)
      (stroke (width 0.15) (type solid)) (fill none) (layer "B.Fab"))
    (pad "1" smd roundrect (at -0.485 0 180) (size 0.59 0.64) (layers "B.Cu" "B.Paste" "B.Mask") (roundrect_rratio 0.25)
      (net 15 "PS_3V3") (pintype "passive"))
    (pad "2" smd roundrect (at 0.485 0 180) (size 0.59 0.64) (layers "B.Cu" "B.Paste" "B.Mask") (roundrect_rratio 0.25)
      (net 221 "/PCIE M2 key E /~{M2_PERST}") (pintype "passive"))
  )
	(footprint "kria-k26-devboard-footprints:R_0402_1005Metric" (layer "B.Cu")
    (at 110.95 144.2 180)
    (descr "Resistor SMD 0402")
    (tags "resistor SMD 0402")
    (property "Author" "Antmicro")
    (property "License" "Apache-2.0")
    (property "MPN" "CR0402-FX-1003GLF")
    (property "Manufacturer" "Bourns")
    (property "Sheetfile" "reset.kicad_sch")
    (property "Sheetname" "Reset logic")
    (property "Tolerance" "1%")
    (property "Val" "100k")
    (property "ki_description" "100k resistor in 0402 package with 1% tolerance")
    (attr smd)
    (fp_text reference "R88" (at -1.12 -1.35) (layer "B.SilkS")
        (effects (font (size 0.7 0.7) (thickness 0.15)) (justify left bottom mirror))
    )
    (fp_text value "R_100k_0402" (at 0 -1.4) (layer "B.Fab") hide
        (effects (font (size 0.7 0.7) (thickness 0.15)) (justify left bottom mirror))
    )
    (fp_text user "License: Apache-2.0" (at -0.95 -5.169) (layer "B.Fab") hide
        (effects (font (size 0.7 0.7) (thickness 0.15)) (justify left bottom mirror))
    )
    (fp_text user "${REFERENCE}" (at -0.95 -3.168) (layer "B.Fab") hide
        (effects (font (size 0.7 0.7) (thickness 0.15)) (justify left bottom mirror))
    )
    (fp_text user "Author: Antmicro" (at -0.95 -4.169) (layer "B.Fab") hide
        (effects (font (size 0.7 0.7) (thickness 0.15)) (justify left bottom mirror))
    )
    (fp_rect (start -0.93 0.47) (end 0.93 -0.47)
      (stroke (width 0.05) (type solid)) (fill none) (layer "B.CrtYd"))
    (fp_rect (start -0.5 0.25) (end 0.5 -0.25)
      (stroke (width 0.15) (type solid)) (fill none) (layer "B.Fab"))
    (pad "1" smd roundrect (at -0.485 0 180) (size 0.59 0.64) (layers "B.Cu" "B.Paste" "B.Mask") (roundrect_rratio 0.25)
      (net 1 "GND") (pintype "passive"))
    (pad "2" smd roundrect (at 0.485 0 180) (size 0.59 0.64) (layers "B.Cu" "B.Paste" "B.Mask") (roundrect_rratio 0.25)
      (net 676 "Net-(U34-A_{1})") (pintype "passive"))
  )
	(footprint "kria-k26-devboard-footprints:C_0402_1005Metric" (layer "B.Cu")
    (at 106.585 141.6 180)
    (descr "Capacitor SMD 0402")
    (tags "capacitor SMD 0402")
    (property "Author" "Antmicro")
    (property "Dielectric" "X5R")
    (property "License" "Apache-2.0")
    (property "MPN" "GRM155R61H104KE14D")
    (property "Manufacturer" "Murata")
    (property "Sheetfile" "reset.kicad_sch")
    (property "Sheetname" "Reset logic")
    (property "Val" "100n")
    (property "Voltage" "50V")
    (property "ki_description" " ")
    (attr smd)
    (fp_text reference "C134" (at -0.585 -1.32) (layer "B.SilkS")
        (effects (font (size 0.7 0.7) (thickness 0.15)) (justify left bottom mirror))
    )
    (fp_text value "C_100n_0402" (at 0 -1.4) (layer "B.Fab") hide
        (effects (font (size 0.7 0.7) (thickness 0.15)) (justify left bottom mirror))
    )
    (fp_text user "${REFERENCE}" (at -0.932 -3.168) (layer "B.Fab") hide
        (effects (font (size 0.7 0.7) (thickness 0.15)) (justify left bottom mirror))
    )
    (fp_text user "Author: Antmicro" (at -0.932 -4.17) (layer "B.Fab") hide
        (effects (font (size 0.7 0.7) (thickness 0.15)) (justify left bottom mirror))
    )
    (fp_text user "License: Apache-2.0" (at -0.932 -5.17) (layer "B.Fab") hide
        (effects (font (size 0.7 0.7) (thickness 0.15)) (justify left bottom mirror))
    )
    (fp_rect (start -0.94 0.47) (end 0.94 -0.47)
      (stroke (width 0.05) (type solid)) (fill none) (layer "B.CrtYd"))
    (fp_rect (start -0.499 0.249) (end 0.499 -0.249)
      (stroke (width 0.15) (type solid)) (fill none) (layer "B.Fab"))
    (pad "1" smd roundrect (at -0.484 0 180) (size 0.59 0.64) (layers "B.Cu" "B.Paste" "B.Mask") (roundrect_rratio 0.25)
      (net 17 "PS_1V8") (pintype "passive"))
    (pad "2" smd roundrect (at 0.484 0 180) (size 0.59 0.64) (layers "B.Cu" "B.Paste" "B.Mask") (roundrect_rratio 0.25)
      (net 1 "GND") (pintype "passive"))
  )
	(footprint "kria-k26-devboard-footprints:R_0402_1005Metric" (layer "B.Cu")
    (at 115.7 142.1 180)
    (descr "Resistor SMD 0402")
    (tags "resistor SMD 0402")
    (property "Author" "Antmicro")
    (property "License" "Apache-2.0")
    (property "MPN" "CR0402-FX-1003GLF")
    (property "Manufacturer" "Bourns")
    (property "Sheetfile" "reset.kicad_sch")
    (property "Sheetname" "Reset logic")
    (property "Tolerance" "1%")
    (property "Val" "100k")
    (property "ki_description" "100k resistor in 0402 package with 1% tolerance")
    (attr smd)
    (fp_text reference "R91" (at -3.07 -0.34) (layer "B.SilkS")
        (effects (font (size 0.7 0.7) (thickness 0.15)) (justify left bottom mirror))
    )
    (fp_text value "R_100k_0402" (at 0 -1.4) (layer "B.Fab") hide
        (effects (font (size 0.7 0.7) (thickness 0.15)) (justify left bottom mirror))
    )
    (fp_text user "Author: Antmicro" (at -0.95 -4.169) (layer "B.Fab") hide
        (effects (font (size 0.7 0.7) (thickness 0.15)) (justify left bottom mirror))
    )
    (fp_text user "${REFERENCE}" (at -0.95 -3.168) (layer "B.Fab") hide
        (effects (font (size 0.7 0.7) (thickness 0.15)) (justify left bottom mirror))
    )
    (fp_text user "License: Apache-2.0" (at -0.95 -5.169) (layer "B.Fab") hide
        (effects (font (size 0.7 0.7) (thickness 0.15)) (justify left bottom mirror))
    )
    (fp_rect (start -0.93 0.47) (end 0.93 -0.47)
      (stroke (width 0.05) (type solid)) (fill none) (layer "B.CrtYd"))
    (fp_rect (start -0.5 0.25) (end 0.5 -0.25)
      (stroke (width 0.15) (type solid)) (fill none) (layer "B.Fab"))
    (pad "1" smd roundrect (at -0.485 0 180) (size 0.59 0.64) (layers "B.Cu" "B.Paste" "B.Mask") (roundrect_rratio 0.25)
      (net 1 "GND") (pintype "passive"))
    (pad "2" smd roundrect (at 0.485 0 180) (size 0.59 0.64) (layers "B.Cu" "B.Paste" "B.Mask") (roundrect_rratio 0.25)
      (net 679 "Net-(U33-2A2)") (pintype "passive"))
  )
)
